(kicad_pcb
	(version 20260206)
	(generator "pcbnew")
	(generator_version "10.0")
	(general
		(thickness 1.6)
		(legacy_teardrops no)
	)
	(paper "A4")
	(title_block
		(title "v1-chassis-manager — T6M_CM_d_v01_1031_1645.brd")
		(comment 1 "Open CloudServer (Microsoft) / footprints 1114-1120 of 2512")
	)
	(layers
		(0 "F.Cu" signal "TOP")
		(4 "In1.Cu" signal "GND1")
		(6 "In2.Cu" signal "IN1")
		(8 "In3.Cu" signal "VCC1")
		(10 "In4.Cu" signal "VCC2")
		(12 "In5.Cu" signal "GND2")
		(14 "In6.Cu" signal "IN2")
		(16 "In7.Cu" signal "IN3")
		(18 "In8.Cu" signal "GND3")
		(2 "B.Cu" signal "BOTTOM")
		(9 "F.Adhes" user "F.Adhesive")
		(11 "B.Adhes" user "B.Adhesive")
		(13 "F.Paste" user "Package Geometry/Pastemask Top")
		(15 "B.Paste" user "Package Geometry/Pastemask Bottom")
		(5 "F.SilkS" user "Ref Des/Silkscreen Top")
		(7 "B.SilkS" user "Ref Des/Silkscreen Bottom")
		(1 "F.Mask" user "Board Geometry/Soldermask Top")
		(3 "B.Mask" user "Board Geometry/Soldermask Bottom")
		(17 "Dwgs.User" user "User.Drawings")
		(19 "Cmts.User" user "User.Comments")
		(21 "Eco1.User" user "User.Eco1")
		(23 "Eco2.User" user "User.Eco2")
		(25 "Edge.Cuts" user "Board Geometry/Outline")
		(27 "Margin" user)
		(31 "F.CrtYd" user "Package Geometry/Place Bound Top")
		(29 "B.CrtYd" user "Package Geometry/Place Bound Bottom")
		(35 "F.Fab" user "Ref Des/Assembly Top")
		(33 "B.Fab" user "Ref Des/Assembly Bottom")
	)
	(footprint ""
		(layer "F.Cu")
		(at 16.81226 -131.82219 -90)
		(property "Reference" "PU6"
			(at -1.12649 -1.823466 90)
			(unlocked yes)
			(layer "F.SilkS")
			(effects
				(font
					(size 0.7874 0.5842)
					(thickness 0.1524)
				)
				(justify left)
			)
		)
		(property "Value" ""
			(at 0 0 270)
			(layer "F.Fab")
			(effects
				(font
					(size 1.27 1.27)
				)
			)
		)
		(duplicate_pad_numbers_are_jumpers no)
		(fp_line
			(start -0.025146 2.325116)
			(end 0.457708 2.325116)
			(stroke
				(width 0.1524)
				(type default)
			)
			(layer "F.SilkS")
		)
		(fp_line
			(start 2.591308 2.325116)
			(end 3.124962 2.325116)
			(stroke
				(width 0.1524)
				(type default)
			)
			(layer "F.SilkS")
		)
		(fp_line
			(start 3.124962 2.325116)
			(end 3.124962 1.893062)
			(stroke
				(width 0.1524)
				(type default)
			)
			(layer "F.SilkS")
		)
		(fp_line
			(start -0.025146 1.842262)
			(end -0.025146 2.325116)
			(stroke
				(width 0.1524)
				(type default)
			)
			(layer "F.SilkS")
		)
		(fp_line
			(start 3.124962 -0.316738)
			(end 3.124962 -0.824992)
			(stroke
				(width 0.1524)
				(type default)
			)
			(layer "F.SilkS")
		)
		(fp_line
			(start -0.025146 -0.824992)
			(end -0.025146 -0.291338)
			(stroke
				(width 0.1524)
				(type default)
			)
			(layer "F.SilkS")
		)
		(fp_line
			(start 0.483108 -0.824992)
			(end -0.025146 -0.824992)
			(stroke
				(width 0.1524)
				(type default)
			)
			(layer "F.SilkS")
		)
		(fp_line
			(start 3.124962 -0.824992)
			(end 2.591308 -0.824992)
			(stroke
				(width 0.1524)
				(type default)
			)
			(layer "F.SilkS")
		)
		(fp_poly
			(pts
				(xy -0.550164 0) (xy -1.690116 -0.379984) (xy -1.690116 0.379984)
			)
			(stroke
				(width 0)
				(type default)
			)
			(fill yes)
			(layer "F.SilkS")
		)
		(fp_poly
			(pts
				(xy -0.025146 2.325116) (xy 0.584708 2.325116) (xy 0.584708 2.832862) (xy 2.515108 2.832862) (xy 2.515108 2.325116)
				(xy 3.124962 2.325116) (xy 3.124962 1.715262) (xy 3.632708 1.715262) (xy 3.632708 -0.215138) (xy 3.124962 -0.215138)
				(xy 3.124962 -0.824992) (xy 2.515108 -0.824992) (xy 2.515108 -1.332738) (xy 0.584708 -1.332738)
				(xy 0.584708 -0.824992) (xy -0.025146 -0.824992) (xy -0.025146 -0.215138) (xy -0.532892 -0.215138)
				(xy -0.532892 1.715262) (xy -0.025146 1.715262)
			)
			(stroke
				(width 0)
				(type default)
			)
			(fill no)
			(layer "F.CrtYd")
		)
		(fp_line
			(start -0.025146 2.325116)
			(end -0.025146 -0.824992)
			(stroke
				(width 0.1)
				(type default)
			)
			(layer "F.Fab")
		)
		(fp_line
			(start 3.124962 2.325116)
			(end -0.025146 2.325116)
			(stroke
				(width 0.1)
				(type default)
			)
			(layer "F.Fab")
		)
		(fp_line
			(start -0.025146 -0.824992)
			(end 3.124962 -0.824992)
			(stroke
				(width 0.1)
				(type default)
			)
			(layer "F.Fab")
		)
		(fp_line
			(start 3.124962 -0.824992)
			(end 3.124962 2.325116)
			(stroke
				(width 0.1)
				(type default)
			)
			(layer "F.Fab")
		)
		(fp_text user "5"
			(at 0.822198 3.301746 0)
			(unlocked yes)
			(layer "F.SilkS")
			(effects
				(font
					(size 0.635 0.4064)
					(thickness 0.1524)
				)
				(justify left)
			)
		)
		(fp_text user "9"
			(at 3.534156 2.742438 0)
			(unlocked yes)
			(layer "F.SilkS")
			(effects
				(font
					(size 0.635 0.4064)
					(thickness 0.1524)
				)
				(justify left)
			)
		)
		(fp_text user "12"
			(at 3.683508 -0.296164 0)
			(unlocked yes)
			(layer "F.SilkS")
			(effects
				(font
					(size 0.635 0.4064)
					(thickness 0.1524)
				)
				(justify left)
			)
		)
		(fp_text user "16"
			(at 0.146304 -0.936752 0)
			(unlocked yes)
			(layer "F.SilkS")
			(effects
				(font
					(size 0.635 0.4064)
					(thickness 0.1524)
				)
				(justify left)
			)
		)
		(pad "1" smd rect
			(at 0 0)
			(size 0.2794 0.9144)
			(layers "F.Cu" "F.Mask" "F.Paste")
			(net "P1V05_NODE1_VREF")
		)
		(pad "2" smd rect
			(at 0 0.500126)
			(size 0.2794 0.9144)
			(layers "F.Cu" "F.Mask" "F.Paste")
			(net "P1V05_NODE1_VREFIN")
		)
		(pad "3" smd rect
			(at 0 0.999998)
			(size 0.2794 0.9144)
			(layers "F.Cu" "F.Mask" "F.Paste")
			(net "VSENSE_P1V05_NODE1_N")
		)
		(pad "4" smd rect
			(at 0 1.500124)
			(size 0.2794 0.9144)
			(layers "F.Cu" "F.Mask" "F.Paste")
			(net "P1V05_NODE1_VSNS")
		)
		(pad "5" smd rect
			(at 0.799846 2.29997 270)
			(size 0.2794 0.9144)
			(layers "F.Cu" "F.Mask" "F.Paste")
			(net "P1V05_NODE1_COMP")
		)
		(pad "6" smd rect
			(at 1.299972 2.29997 270)
			(size 0.2794 0.9144)
			(layers "F.Cu" "F.Mask" "F.Paste")
			(net "P1V05_NODE1_TRIP")
		)
		(pad "7" smd rect
			(at 1.799844 2.29997 270)
			(size 0.2794 0.9144)
			(layers "F.Cu" "F.Mask" "F.Paste")
			(net "GND")
		)
		(pad "8" smd rect
			(at 2.29997 2.29997 270)
			(size 0.2794 0.9144)
			(layers "F.Cu" "F.Mask" "F.Paste")
			(net "GND")
		)
		(pad "9" smd rect
			(at 3.099816 1.500124)
			(size 0.2794 0.9144)
			(layers "F.Cu" "F.Mask" "F.Paste")
			(net "P5V_STB_NODE1")
		)
		(pad "10" smd rect
			(at 3.099816 0.999998)
			(size 0.2794 0.9144)
			(layers "F.Cu" "F.Mask" "F.Paste")
			(net "SW_P1V05_NODE1_DRVL")
		)
		(pad "11" smd rect
			(at 3.099816 0.500126)
			(size 0.2794 0.9144)
			(layers "F.Cu" "F.Mask" "F.Paste")
			(net "SW_P1V05_NODE1_DRVH")
		)
		(pad "12" smd rect
			(at 3.099816 0)
			(size 0.2794 0.9144)
			(layers "F.Cu" "F.Mask" "F.Paste")
			(net "SW_P1V05_NODE1_PH")
		)
		(pad "13" smd rect
			(at 2.29997 -0.799846 270)
			(size 0.2794 0.9144)
			(layers "F.Cu" "F.Mask" "F.Paste")
			(net "SW_P1V05_NODE1_BT")
		)
		(pad "14" smd rect
			(at 1.799844 -0.799846 270)
			(size 0.2794 0.9144)
			(layers "F.Cu" "F.Mask" "F.Paste")
			(net "P1V05_NODE1_EN")
		)
		(pad "15" smd rect
			(at 1.299972 -0.799846 270)
			(size 0.2794 0.9144)
			(layers "F.Cu" "F.Mask" "F.Paste")
			(net "P1V05_NODE1_MODE")
		)
		(pad "16" smd rect
			(at 0.799846 -0.799846 270)
			(size 0.2794 0.9144)
			(layers "F.Cu" "F.Mask" "F.Paste")
			(net "PWRGD_NODE1_P1V05_PG")
		)
		(pad "TH" smd rect
			(at 1.549908 0.750062)
			(size 1.651 1.651)
			(layers "F.Cu" "F.Mask" "F.Paste")
			(net "GND")
		)
		(zone
			(layer "F.Cu")
			(hatch none 0.5)
			(connect_pads
				(clearance 0)
			)
			(min_thickness 0.25)
			(keepout
				(tracks not_allowed)
				(vias allowed)
				(pads allowed)
				(copperpour not_allowed)
				(footprints allowed)
			)
			(placement
				(enabled no)
				(sheetname "")
			)
			(fill
				(thermal_gap 0.5)
				(thermal_bridge_width 0.5)
				(island_removal_mode 0)
			)
			(polygon
				(pts
					(xy 15.28826 -131.288282) (xy 17.078198 -131.288282) (xy 17.078198 -129.256282) (xy 15.046198 -129.256282)
					(xy 15.046198 -131.288282) (xy 15.21206 -131.288282) (xy 15.21206 -131.16179) (xy 15.16126 -131.16179)
					(xy 15.16126 -129.38379) (xy 16.96466 -129.38379) (xy 16.96466 -131.16179) (xy 15.23746 -131.16179)
					(xy 15.23746 -131.288282)
				)
			)
		)
		(zone
			(layer "F.Cu")
			(hatch none 0.5)
			(connect_pads
				(clearance 0)
			)
			(min_thickness 0.25)
			(keepout
				(tracks allowed)
				(vias not_allowed)
				(pads allowed)
				(copperpour not_allowed)
				(footprints allowed)
			)
			(placement
				(enabled no)
				(sheetname "")
			)
			(fill
				(thermal_gap 0.5)
				(thermal_bridge_width 0.5)
				(island_removal_mode 0)
			)
			(polygon
				(pts
					(xy 15.28826 -131.288282) (xy 17.078198 -131.288282) (xy 17.078198 -129.256282) (xy 15.046198 -129.256282)
					(xy 15.046198 -131.288282) (xy 15.21206 -131.288282) (xy 15.21206 -131.237482) (xy 15.21206 -131.16179)
					(xy 15.16126 -131.16179) (xy 15.16126 -129.38379) (xy 16.96466 -129.38379) (xy 16.96466 -131.16179)
					(xy 15.28826 -131.16179) (xy 15.23746 -131.16179) (xy 15.23746 -131.288282)
				)
			)
		)
	)
	(footprint ""
		(layer "F.Cu")
		(at 168.662096 -131.715764 90)
		(property "Reference" "R660"
			(at -2.014728 -3.01879 90)
			(unlocked yes)
			(layer "F.SilkS")
			(effects
				(font
					(size 0.7874 0.5842)
					(thickness 0.1524)
				)
				(justify left)
			)
		)
		(property "Value" ""
			(at 0 0 90)
			(layer "F.Fab")
			(effects
				(font
					(size 1.27 1.27)
				)
			)
		)
		(duplicate_pad_numbers_are_jumpers no)
		(fp_line
			(start 0.7874 -0.4064)
			(end 0.7874 0.4064)
			(stroke
				(width 0.1524)
				(type default)
			)
			(layer "F.SilkS")
		)
		(fp_line
			(start -0.7874 -0.4064)
			(end 0.7874 -0.4064)
			(stroke
				(width 0.1524)
				(type default)
			)
			(layer "F.SilkS")
		)
		(fp_line
			(start 0.7874 0.4064)
			(end -0.7874 0.4064)
			(stroke
				(width 0.1524)
				(type default)
			)
			(layer "F.SilkS")
		)
		(fp_line
			(start -0.7874 0.4064)
			(end -0.7874 -0.4064)
			(stroke
				(width 0.1524)
				(type default)
			)
			(layer "F.SilkS")
		)
		(fp_poly
			(pts
				(xy -0.508 0.2794) (xy -0.508 0.2286) (xy -0.635 0.2286) (xy -0.635 -0.254) (xy -0.5334 -0.254)
				(xy -0.5334 -0.2794) (xy 0.5334 -0.2794) (xy 0.5334 -0.254) (xy 0.635 -0.254) (xy 0.635 0.254) (xy 0.5334 0.254)
				(xy 0.5334 0.2794)
			)
			(stroke
				(width 0)
				(type default)
			)
			(fill no)
			(layer "F.CrtYd")
		)
		(pad "1" smd rect
			(at 0.40005 0 90)
			(size 0.4572 0.508)
			(layers "F.Cu" "F.Mask" "F.Paste")
			(net "CPLD123_RSV2")
		)
		(pad "2" smd rect
			(at -0.40005 0 90)
			(size 0.4572 0.508)
			(layers "F.Cu" "F.Mask" "F.Paste")
			(net "CPLD1_RSV2")
		)
	)
	(footprint ""
		(layer "F.Cu")
		(at 177.649632 -148.94052)
		(property "Reference" "C445"
			(at -5.225542 0.262128 0)
			(unlocked yes)
			(layer "F.SilkS")
			(effects
				(font
					(size 0.7874 0.5842)
					(thickness 0.1524)
				)
				(justify left)
			)
		)
		(property "Value" ""
			(at 0 0 0)
			(layer "F.Fab")
			(effects
				(font
					(size 1.27 1.27)
				)
			)
		)
		(duplicate_pad_numbers_are_jumpers no)
		(fp_line
			(start -1.905 -0.8636)
			(end 1.905 -0.8636)
			(stroke
				(width 0.1524)
				(type default)
			)
			(layer "F.SilkS")
		)
		(fp_line
			(start -1.905 0.8636)
			(end -1.905 -0.8636)
			(stroke
				(width 0.1524)
				(type default)
			)
			(layer "F.SilkS")
		)
		(fp_line
			(start 0 0.8382)
			(end 0 -0.8382)
			(stroke
				(width 0.1524)
				(type default)
			)
			(layer "F.SilkS")
		)
		(fp_line
			(start 1.905 -0.8636)
			(end 1.905 0.8636)
			(stroke
				(width 0.1524)
				(type default)
			)
			(layer "F.SilkS")
		)
		(fp_line
			(start 1.905 0.8636)
			(end -1.905 0.8636)
			(stroke
				(width 0.1524)
				(type default)
			)
			(layer "F.SilkS")
		)
		(fp_rect
			(start -1.524 0.7366)
			(end 1.524 -0.7366)
			(stroke
				(width 0)
				(type default)
			)
			(fill no)
			(layer "F.CrtYd")
		)
		(pad "1" smd rect
			(at 0.94996 0)
			(size 1.1176 1.3716)
			(layers "F.Cu" "F.Mask" "F.Paste")
			(net "P3V3_NODE1")
		)
		(pad "2" smd rect
			(at -0.94996 0)
			(size 1.1176 1.3716)
			(layers "F.Cu" "F.Mask" "F.Paste")
			(net "GND")
		)
	)
	(footprint ""
		(layer "F.Cu")
		(at 134.98576 -110.783624 -90)
		(property "Reference" "R16"
			(at 5.84835 -0.628142 90)
			(unlocked yes)
			(layer "F.SilkS")
			(effects
				(font
					(size 0.7874 0.5842)
					(thickness 0.1524)
				)
				(justify left)
			)
		)
		(property "Value" ""
			(at 0 0 270)
			(layer "F.Fab")
			(effects
				(font
					(size 1.27 1.27)
				)
			)
		)
		(duplicate_pad_numbers_are_jumpers no)
		(fp_line
			(start -0.7874 0.4064)
			(end -0.7874 -0.4064)
			(stroke
				(width 0.1524)
				(type default)
			)
			(layer "F.SilkS")
		)
		(fp_line
			(start 0.7874 0.4064)
			(end -0.7874 0.4064)
			(stroke
				(width 0.1524)
				(type default)
			)
			(layer "F.SilkS")
		)
		(fp_line
			(start -0.7874 -0.4064)
			(end 0.7874 -0.4064)
			(stroke
				(width 0.1524)
				(type default)
			)
			(layer "F.SilkS")
		)
		(fp_line
			(start 0.7874 -0.4064)
			(end 0.7874 0.4064)
			(stroke
				(width 0.1524)
				(type default)
			)
			(layer "F.SilkS")
		)
		(fp_poly
			(pts
				(xy -0.508 0.2794) (xy -0.508 0.2286) (xy -0.635 0.2286) (xy -0.635 -0.254) (xy -0.5334 -0.254)
				(xy -0.5334 -0.2794) (xy 0.5334 -0.2794) (xy 0.5334 -0.254) (xy 0.635 -0.254) (xy 0.635 0.254) (xy 0.5334 0.254)
				(xy 0.5334 0.2794)
			)
			(stroke
				(width 0)
				(type default)
			)
			(fill no)
			(layer "F.CrtYd")
		)
		(pad "1" smd rect
			(at 0.40005 0 270)
			(size 0.4572 0.508)
			(layers "F.Cu" "F.Mask" "F.Paste")
			(net "GND")
		)
		(pad "2" smd rect
			(at -0.40005 0 270)
			(size 0.4572 0.508)
			(layers "F.Cu" "F.Mask" "F.Paste")
			(net "CLK_FSLB_NODE1")
		)
	)
	(footprint ""
		(layer "F.Cu")
		(at 149.508972 -29.903928 180)
		(property "Reference" "C531"
			(at 1.243076 -2.064258 0)
			(unlocked yes)
			(layer "F.SilkS")
			(effects
				(font
					(size 0.7874 0.5842)
					(thickness 0.1524)
				)
				(justify left)
			)
		)
		(property "Value" ""
			(at 0 0 180)
			(layer "F.Fab")
			(effects
				(font
					(size 1.27 1.27)
				)
			)
		)
		(duplicate_pad_numbers_are_jumpers no)
		(fp_line
			(start 0.7874 0.4064)
			(end -0.7874 0.4064)
			(stroke
				(width 0.1524)
				(type default)
			)
			(layer "F.SilkS")
		)
		(fp_line
			(start 0.7874 -0.4064)
			(end 0.7874 0.4064)
			(stroke
				(width 0.1524)
				(type default)
			)
			(layer "F.SilkS")
		)
		(fp_line
			(start 0 0.381)
			(end 0 -0.381)
			(stroke
				(width 0.1524)
				(type default)
			)
			(layer "F.SilkS")
		)
		(fp_line
			(start -0.7874 0.4064)
			(end -0.7874 -0.4064)
			(stroke
				(width 0.1524)
				(type default)
			)
			(layer "F.SilkS")
		)
		(fp_line
			(start -0.7874 -0.4064)
			(end 0.7874 -0.4064)
			(stroke
				(width 0.1524)
				(type default)
			)
			(layer "F.SilkS")
		)
		(fp_poly
			(pts
				(xy -0.5334 0.254) (xy -0.635 0.254) (xy -0.635 0.2286) (xy -0.635 -0.254) (xy -0.5334 -0.254) (xy -0.5334 -0.2794)
				(xy 0.5334 -0.2794) (xy 0.5334 -0.254) (xy 0.635 -0.254) (xy 0.635 0.254) (xy 0.5334 0.254) (xy 0.5334 0.2794)
				(xy -0.508 0.2794) (xy -0.5334 0.2794)
			)
			(stroke
				(width 0)
				(type default)
			)
			(fill no)
			(layer "F.CrtYd")
		)
		(pad "1" smd rect
			(at 0.40005 0 180)
			(size 0.4572 0.508)
			(layers "F.Cu" "F.Mask" "F.Paste")
			(net "GND")
		)
		(pad "2" smd rect
			(at -0.40005 0 180)
			(size 0.4572 0.508)
			(layers "F.Cu" "F.Mask" "F.Paste")
			(net "N21624890")
		)
	)
	(footprint ""
		(layer "F.Cu")
		(at 79.945992 -78.192122)
		(property "Reference" "R76"
			(at -0.298196 16.248888 0)
			(unlocked yes)
			(layer "F.SilkS")
			(effects
				(font
					(size 0.7874 0.5842)
					(thickness 0.1524)
				)
				(justify left)
			)
		)
		(property "Value" ""
			(at 0 0 0)
			(layer "F.Fab")
			(effects
				(font
					(size 1.27 1.27)
				)
			)
		)
		(duplicate_pad_numbers_are_jumpers no)
		(fp_line
			(start -0.7874 -0.4064)
			(end 0.7874 -0.4064)
			(stroke
				(width 0.1524)
				(type default)
			)
			(layer "F.SilkS")
		)
		(fp_line
			(start -0.7874 0.4064)
			(end -0.7874 -0.4064)
			(stroke
				(width 0.1524)
				(type default)
			)
			(layer "F.SilkS")
		)
		(fp_line
			(start 0.7874 -0.4064)
			(end 0.7874 0.4064)
			(stroke
				(width 0.1524)
				(type default)
			)
			(layer "F.SilkS")
		)
		(fp_line
			(start 0.7874 0.4064)
			(end -0.7874 0.4064)
			(stroke
				(width 0.1524)
				(type default)
			)
			(layer "F.SilkS")
		)
		(fp_poly
			(pts
				(xy -0.508 0.2794) (xy -0.508 0.2286) (xy -0.635 0.2286) (xy -0.635 -0.254) (xy -0.5334 -0.254)
				(xy -0.5334 -0.2794) (xy 0.5334 -0.2794) (xy 0.5334 -0.254) (xy 0.635 -0.254) (xy 0.635 0.254) (xy 0.5334 0.254)
				(xy 0.5334 0.2794)
			)
			(stroke
				(width 0)
				(type default)
			)
			(fill no)
			(layer "F.CrtYd")
		)
		(pad "1" smd rect
			(at 0.40005 0)
			(size 0.4572 0.508)
			(layers "F.Cu" "F.Mask" "F.Paste")
			(net "P1V05_NODE1")
		)
		(pad "2" smd rect
			(at -0.40005 0)
			(size 0.4572 0.508)
			(layers "F.Cu" "F.Mask" "F.Paste")
			(net "XDP_SOC_CPU_NODE1_TDI")
		)
	)
	(footprint ""
		(layer "F.Cu")
		(at 65.305686 -148.476462 90)
		(property "Reference" "R313"
			(at -0.86106 1.523238 90)
			(unlocked yes)
			(layer "F.SilkS")
			(effects
				(font
					(size 0.7874 0.5842)
					(thickness 0.1524)
				)
				(justify left)
			)
		)
		(property "Value" ""
			(at 0 0 90)
			(layer "F.Fab")
			(effects
				(font
					(size 1.27 1.27)
				)
			)
		)
		(duplicate_pad_numbers_are_jumpers no)
		(fp_line
			(start 0.7874 -0.4064)
			(end 0.7874 0.4064)
			(stroke
				(width 0.1524)
				(type default)
			)
			(layer "F.SilkS")
		)
		(fp_line
			(start -0.7874 -0.4064)
			(end 0.7874 -0.4064)
			(stroke
				(width 0.1524)
				(type default)
			)
			(layer "F.SilkS")
		)
		(fp_line
			(start 0.7874 0.4064)
			(end -0.7874 0.4064)
			(stroke
				(width 0.1524)
				(type default)
			)
			(layer "F.SilkS")
		)
		(fp_line
			(start -0.7874 0.4064)
			(end -0.7874 -0.4064)
			(stroke
				(width 0.1524)
				(type default)
			)
			(layer "F.SilkS")
		)
		(fp_poly
			(pts
				(xy -0.508 0.2794) (xy -0.508 0.2286) (xy -0.635 0.2286) (xy -0.635 -0.254) (xy -0.5334 -0.254)
				(xy -0.5334 -0.2794) (xy 0.5334 -0.2794) (xy 0.5334 -0.254) (xy 0.635 -0.254) (xy 0.635 0.254) (xy 0.5334 0.254)
				(xy 0.5334 0.2794)
			)
			(stroke
				(width 0)
				(type default)
			)
			(fill no)
			(layer "F.CrtYd")
		)
		(pad "1" smd rect
			(at 0.40005 0 90)
			(size 0.4572 0.508)
			(layers "F.Cu" "F.Mask" "F.Paste")
			(net "GND")
		)
		(pad "2" smd rect
			(at -0.40005 0 90)
			(size 0.4572 0.508)
			(layers "F.Cu" "F.Mask" "F.Paste")
			(net "BMC_NODE1_ADCREXT")
		)
	)
)
